(kicad_pcb
	(version 20260206)
	(generator "pcbnew")
	(generator_version "10.0")
	(general
		(thickness 1.6)
		(legacy_teardrops no)
	)
	(paper "A4")
	(title_block
		(title "12092022_DA0F0TMDCD0_F0T_Management_Board_D_brd_V3_OCP.brd")
		(comment 1 "Grand Teton / footprints 437-441 of 1440")
	)
	(layers
		(0 "F.Cu" signal "TOP")
		(4 "In1.Cu" signal "GND")
		(6 "In2.Cu" signal "IN1")
		(8 "In3.Cu" signal "GND1")
		(10 "In4.Cu" signal "IN2")
		(12 "In5.Cu" signal "VCC")
		(14 "In6.Cu" signal "VCC1")
		(16 "In7.Cu" signal "IN3")
		(18 "In8.Cu" signal "GND2")
		(20 "In9.Cu" signal "IN4")
		(22 "In10.Cu" signal "GND3")
		(2 "B.Cu" signal "BOTTOM")
		(9 "F.Adhes" user "F.Adhesive")
		(11 "B.Adhes" user "B.Adhesive")
		(13 "F.Paste" user "Package Geometry/Pastemask Top")
		(15 "B.Paste" user "Package Geometry/Pastemask Bottom")
		(5 "F.SilkS" user "Ref Des/Silkscreen Top")
		(7 "B.SilkS" user "Ref Des/Silkscreen Bottom")
		(1 "F.Mask" user "Board Geometry/Soldermask Top")
		(3 "B.Mask" user "Board Geometry/Soldermask Bottom")
		(17 "Dwgs.User" user "User.Drawings")
		(19 "Cmts.User" user "User.Comments")
		(21 "Eco1.User" user "User.Eco1")
		(23 "Eco2.User" user "User.Eco2")
		(25 "Edge.Cuts" user "Board Geometry/Outline")
		(27 "Margin" user)
		(31 "F.CrtYd" user "Package Geometry/Place Bound Top")
		(29 "B.CrtYd" user "Package Geometry/Place Bound Bottom")
		(35 "F.Fab" user "Ref Des/Assembly Top")
		(33 "B.Fab" user "Ref Des/Assembly Bottom")
	)
	(footprint ""
		(layer "F.Cu")
		(at 7.17677 -72.06107 90)
		(property "Reference" "PL35"
			(at -0.90297 4.18592 90)
			(unlocked yes)
			(layer "F.SilkS")
			(effects
				(font
					(size 0.7874 0.5842)
					(thickness 0.1524)
				)
				(justify left)
			)
		)
		(property "Value" ""
			(at 0 0 90)
			(layer "F.Fab")
			(effects
				(font
					(size 1.27 1.27)
				)
			)
		)
		(duplicate_pad_numbers_are_jumpers no)
		(fp_line
			(start 3.64998 -3.350006)
			(end 3.64998 -1.8034)
			(stroke
				(width 0.1524)
				(type default)
			)
			(layer "F.SilkS")
		)
		(fp_line
			(start -3.6576 -3.350006)
			(end 3.64998 -3.350006)
			(stroke
				(width 0.1524)
				(type default)
			)
			(layer "F.SilkS")
		)
		(fp_line
			(start -3.64998 -1.8034)
			(end -3.64998 -3.350006)
			(stroke
				(width 0.1524)
				(type default)
			)
			(layer "F.SilkS")
		)
		(fp_line
			(start 3.64998 1.8034)
			(end 3.64998 3.350006)
			(stroke
				(width 0.1524)
				(type default)
			)
			(layer "F.SilkS")
		)
		(fp_line
			(start 3.64998 3.350006)
			(end -3.64998 3.350006)
			(stroke
				(width 0.1524)
				(type default)
			)
			(layer "F.SilkS")
		)
		(fp_line
			(start -3.64998 3.350006)
			(end -3.64998 1.8288)
			(stroke
				(width 0.1524)
				(type default)
			)
			(layer "F.SilkS")
		)
		(fp_line
			(start 3.64998 -3.350006)
			(end 3.64998 3.350006)
			(stroke
				(width 0.1)
				(type default)
			)
			(layer "F.Fab")
		)
		(fp_line
			(start -3.64998 -3.350006)
			(end 3.64998 -3.350006)
			(stroke
				(width 0.1)
				(type default)
			)
			(layer "F.Fab")
		)
		(fp_line
			(start 3.64998 3.350006)
			(end -3.64998 3.350006)
			(stroke
				(width 0.1)
				(type default)
			)
			(layer "F.Fab")
		)
		(fp_line
			(start -3.64998 3.350006)
			(end -3.64998 -3.350006)
			(stroke
				(width 0.1)
				(type default)
			)
			(layer "F.Fab")
		)
		(pad "1" smd rect
			(at -2.92481 0 90)
			(size 2.15392 3.302)
			(layers "F.Cu" "F.Mask" "F.Paste")
			(net "SW_P3V3_AUX_SW")
		)
		(pad "2" smd rect
			(at 2.92481 0 90)
			(size 2.15392 3.302)
			(layers "F.Cu" "F.Mask" "F.Paste")
			(net "P3V3_AUX")
		)
	)
	(footprint ""
		(layer "F.Cu")
		(at 31.75 -33.274)
		(property "Reference" "R89"
			(at 0 0 0)
			(layer "F.SilkS")
			(hide yes)
			(effects
				(font
					(size 1.27 1.27)
				)
			)
		)
		(property "Value" ""
			(at 0 0 0)
			(layer "F.Fab")
			(effects
				(font
					(size 1.27 1.27)
				)
			)
		)
		(duplicate_pad_numbers_are_jumpers no)
		(fp_line
			(start -0.7874 -0.4064)
			(end 0.7874 -0.4064)
			(stroke
				(width 0.1524)
				(type default)
			)
			(layer "F.SilkS")
		)
		(fp_line
			(start -0.7874 0.4064)
			(end -0.7874 -0.4064)
			(stroke
				(width 0.1524)
				(type default)
			)
			(layer "F.SilkS")
		)
		(fp_line
			(start 0.7874 -0.4064)
			(end 0.7874 0.4064)
			(stroke
				(width 0.1524)
				(type default)
			)
			(layer "F.SilkS")
		)
		(fp_line
			(start 0.7874 0.4064)
			(end -0.7874 0.4064)
			(stroke
				(width 0.1524)
				(type default)
			)
			(layer "F.SilkS")
		)
		(fp_line
			(start -0.67945 -0.305054)
			(end -0.12065 -0.305054)
			(stroke
				(width 0.1)
				(type default)
			)
			(layer "F.Fab")
		)
		(fp_line
			(start -0.67945 0.3048)
			(end -0.67945 -0.305054)
			(stroke
				(width 0.1)
				(type default)
			)
			(layer "F.Fab")
		)
		(fp_line
			(start -0.12065 -0.305054)
			(end -0.12065 -0.2794)
			(stroke
				(width 0.1)
				(type default)
			)
			(layer "F.Fab")
		)
		(fp_line
			(start -0.12065 -0.2794)
			(end 0.12065 -0.2794)
			(stroke
				(width 0.1)
				(type default)
			)
			(layer "F.Fab")
		)
		(fp_line
			(start -0.12065 0.2794)
			(end -0.12065 0.3048)
			(stroke
				(width 0.1)
				(type default)
			)
			(layer "F.Fab")
		)
		(fp_line
			(start -0.12065 0.3048)
			(end -0.67945 0.3048)
			(stroke
				(width 0.1)
				(type default)
			)
			(layer "F.Fab")
		)
		(fp_line
			(start 0.120396 0.2794)
			(end -0.12065 0.2794)
			(stroke
				(width 0.1)
				(type default)
			)
			(layer "F.Fab")
		)
		(fp_line
			(start 0.120396 0.3048)
			(end 0.120396 0.2794)
			(stroke
				(width 0.1)
				(type default)
			)
			(layer "F.Fab")
		)
		(fp_line
			(start 0.12065 -0.3048)
			(end 0.67945 -0.3048)
			(stroke
				(width 0.1)
				(type default)
			)
			(layer "F.Fab")
		)
		(fp_line
			(start 0.12065 -0.2794)
			(end 0.12065 -0.3048)
			(stroke
				(width 0.1)
				(type default)
			)
			(layer "F.Fab")
		)
		(fp_line
			(start 0.67945 -0.3048)
			(end 0.67945 0.3048)
			(stroke
				(width 0.1)
				(type default)
			)
			(layer "F.Fab")
		)
		(fp_line
			(start 0.67945 0.3048)
			(end 0.120396 0.3048)
			(stroke
				(width 0.1)
				(type default)
			)
			(layer "F.Fab")
		)
		(pad "1" smd circle
			(at -0.40005 0)
			(size 0 0)
			(layers "F.Cu" "F.Mask" "F.Paste")
			(net "V_DACR_IO")
		)
		(pad "2" smd circle
			(at 0.40005 0)
			(size 0 0)
			(layers "F.Cu" "F.Mask" "F.Paste")
			(net "GND")
		)
	)
	(footprint ""
		(layer "F.Cu")
		(at 12.319 -86.36)
		(property "Reference" "R454"
			(at 0 0 0)
			(layer "F.SilkS")
			(hide yes)
			(effects
				(font
					(size 1.27 1.27)
				)
			)
		)
		(property "Value" ""
			(at 0 0 0)
			(layer "F.Fab")
			(effects
				(font
					(size 1.27 1.27)
				)
			)
		)
		(duplicate_pad_numbers_are_jumpers no)
		(fp_line
			(start -0.7874 -0.4064)
			(end 0.7874 -0.4064)
			(stroke
				(width 0.1524)
				(type default)
			)
			(layer "F.SilkS")
		)
		(fp_line
			(start -0.7874 0.4064)
			(end -0.7874 -0.4064)
			(stroke
				(width 0.1524)
				(type default)
			)
			(layer "F.SilkS")
		)
		(fp_line
			(start 0.7874 -0.4064)
			(end 0.7874 0.4064)
			(stroke
				(width 0.1524)
				(type default)
			)
			(layer "F.SilkS")
		)
		(fp_line
			(start 0.7874 0.4064)
			(end -0.7874 0.4064)
			(stroke
				(width 0.1524)
				(type default)
			)
			(layer "F.SilkS")
		)
		(fp_line
			(start -0.67945 -0.305054)
			(end -0.12065 -0.305054)
			(stroke
				(width 0.1)
				(type default)
			)
			(layer "F.Fab")
		)
		(fp_line
			(start -0.67945 0.3048)
			(end -0.67945 -0.305054)
			(stroke
				(width 0.1)
				(type default)
			)
			(layer "F.Fab")
		)
		(fp_line
			(start -0.12065 -0.305054)
			(end -0.12065 -0.2794)
			(stroke
				(width 0.1)
				(type default)
			)
			(layer "F.Fab")
		)
		(fp_line
			(start -0.12065 -0.2794)
			(end 0.12065 -0.2794)
			(stroke
				(width 0.1)
				(type default)
			)
			(layer "F.Fab")
		)
		(fp_line
			(start -0.12065 0.2794)
			(end -0.12065 0.3048)
			(stroke
				(width 0.1)
				(type default)
			)
			(layer "F.Fab")
		)
		(fp_line
			(start -0.12065 0.3048)
			(end -0.67945 0.3048)
			(stroke
				(width 0.1)
				(type default)
			)
			(layer "F.Fab")
		)
		(fp_line
			(start 0.120396 0.2794)
			(end -0.12065 0.2794)
			(stroke
				(width 0.1)
				(type default)
			)
			(layer "F.Fab")
		)
		(fp_line
			(start 0.120396 0.3048)
			(end 0.120396 0.2794)
			(stroke
				(width 0.1)
				(type default)
			)
			(layer "F.Fab")
		)
		(fp_line
			(start 0.12065 -0.3048)
			(end 0.67945 -0.3048)
			(stroke
				(width 0.1)
				(type default)
			)
			(layer "F.Fab")
		)
		(fp_line
			(start 0.12065 -0.2794)
			(end 0.12065 -0.3048)
			(stroke
				(width 0.1)
				(type default)
			)
			(layer "F.Fab")
		)
		(fp_line
			(start 0.67945 -0.3048)
			(end 0.67945 0.3048)
			(stroke
				(width 0.1)
				(type default)
			)
			(layer "F.Fab")
		)
		(fp_line
			(start 0.67945 0.3048)
			(end 0.120396 0.3048)
			(stroke
				(width 0.1)
				(type default)
			)
			(layer "F.Fab")
		)
		(pad "1" smd circle
			(at -0.40005 0)
			(size 0 0)
			(layers "F.Cu" "F.Mask" "F.Paste")
			(net "SMB_BMC_ALERT4_N")
		)
		(pad "2" smd circle
			(at 0.40005 0)
			(size 0 0)
			(layers "F.Cu" "F.Mask" "F.Paste")
			(net "SMB_BMC_ALERT4_R1_N")
		)
	)
	(footprint ""
		(layer "F.Cu")
		(at 52.809648 -63.912496 90)
		(property "Reference" "R178"
			(at 0 0 90)
			(layer "F.SilkS")
			(hide yes)
			(effects
				(font
					(size 1.27 1.27)
				)
			)
		)
		(property "Value" ""
			(at 0 0 90)
			(layer "F.Fab")
			(effects
				(font
					(size 1.27 1.27)
				)
			)
		)
		(duplicate_pad_numbers_are_jumpers no)
		(fp_line
			(start 0.7874 -0.4064)
			(end 0.7874 0.4064)
			(stroke
				(width 0.1524)
				(type default)
			)
			(layer "F.SilkS")
		)
		(fp_line
			(start -0.7874 -0.4064)
			(end 0.7874 -0.4064)
			(stroke
				(width 0.1524)
				(type default)
			)
			(layer "F.SilkS")
		)
		(fp_line
			(start 0.7874 0.4064)
			(end -0.7874 0.4064)
			(stroke
				(width 0.1524)
				(type default)
			)
			(layer "F.SilkS")
		)
		(fp_line
			(start -0.7874 0.4064)
			(end -0.7874 -0.4064)
			(stroke
				(width 0.1524)
				(type default)
			)
			(layer "F.SilkS")
		)
		(fp_line
			(start -0.12065 -0.305054)
			(end -0.12065 -0.2794)
			(stroke
				(width 0.1)
				(type default)
			)
			(layer "F.Fab")
		)
		(fp_line
			(start -0.67945 -0.305054)
			(end -0.12065 -0.305054)
			(stroke
				(width 0.1)
				(type default)
			)
			(layer "F.Fab")
		)
		(fp_line
			(start 0.67945 -0.3048)
			(end 0.67945 0.3048)
			(stroke
				(width 0.1)
				(type default)
			)
			(layer "F.Fab")
		)
		(fp_line
			(start 0.12065 -0.3048)
			(end 0.67945 -0.3048)
			(stroke
				(width 0.1)
				(type default)
			)
			(layer "F.Fab")
		)
		(fp_line
			(start 0.12065 -0.2794)
			(end 0.12065 -0.3048)
			(stroke
				(width 0.1)
				(type default)
			)
			(layer "F.Fab")
		)
		(fp_line
			(start -0.12065 -0.2794)
			(end 0.12065 -0.2794)
			(stroke
				(width 0.1)
				(type default)
			)
			(layer "F.Fab")
		)
		(fp_line
			(start 0.120396 0.2794)
			(end -0.12065 0.2794)
			(stroke
				(width 0.1)
				(type default)
			)
			(layer "F.Fab")
		)
		(fp_line
			(start -0.12065 0.2794)
			(end -0.12065 0.3048)
			(stroke
				(width 0.1)
				(type default)
			)
			(layer "F.Fab")
		)
		(fp_line
			(start 0.67945 0.3048)
			(end 0.120396 0.3048)
			(stroke
				(width 0.1)
				(type default)
			)
			(layer "F.Fab")
		)
		(fp_line
			(start 0.120396 0.3048)
			(end 0.120396 0.2794)
			(stroke
				(width 0.1)
				(type default)
			)
			(layer "F.Fab")
		)
		(fp_line
			(start -0.12065 0.3048)
			(end -0.67945 0.3048)
			(stroke
				(width 0.1)
				(type default)
			)
			(layer "F.Fab")
		)
		(fp_line
			(start -0.67945 0.3048)
			(end -0.67945 -0.305054)
			(stroke
				(width 0.1)
				(type default)
			)
			(layer "F.Fab")
		)
		(pad "1" smd circle
			(at -0.40005 0 90)
			(size 0 0)
			(layers "F.Cu" "F.Mask" "F.Paste")
			(net "SPI_BMC_CLK_R")
		)
		(pad "2" smd circle
			(at 0.40005 0 90)
			(size 0 0)
			(layers "F.Cu" "F.Mask" "F.Paste")
			(net "SPI_BMC_BOOT_CLK")
		)
	)
	(footprint ""
		(layer "F.Cu")
		(at 39.500048 -97.909888 90)
		(property "Reference" "J40"
			(at 4.896358 10.069068 90)
			(unlocked yes)
			(layer "F.SilkS")
			(effects
				(font
					(size 0.7874 0.5842)
					(thickness 0.1524)
				)
				(justify left)
			)
		)
		(property "Value" ""
			(at 0 0 90)
			(layer "F.Fab")
			(effects
				(font
					(size 1.27 1.27)
				)
			)
		)
		(duplicate_pad_numbers_are_jumpers no)
		(fp_line
			(start 6.945122 -7.649972)
			(end 0 -7.649972)
			(stroke
				(width 0.1524)
				(type default)
			)
			(layer "F.SilkS")
		)
		(fp_line
			(start 6.945122 -7.649972)
			(end 6.945122 7.649972)
			(stroke
				(width 0.1524)
				(type default)
			)
			(layer "F.SilkS")
		)
		(fp_line
			(start 0 -7.649972)
			(end 8.320278 -7.649972)
			(stroke
				(width 0.1524)
				(type default)
			)
			(layer "F.SilkS")
		)
		(fp_line
			(start -6.945122 -7.649972)
			(end 0 -7.649972)
			(stroke
				(width 0.1524)
				(type default)
			)
			(layer "F.SilkS")
		)
		(fp_line
			(start -6.945122 -7.649972)
			(end -6.945122 7.649972)
			(stroke
				(width 0.1524)
				(type default)
			)
			(layer "F.SilkS")
		)
		(fp_line
			(start -10.508742 -7.649972)
			(end 0 -7.649972)
			(stroke
				(width 0.1524)
				(type default)
			)
			(layer "F.SilkS")
		)
		(fp_line
			(start -11.554968 -7.649972)
			(end -11.296142 -7.649972)
			(stroke
				(width 0.1524)
				(type default)
			)
			(layer "F.SilkS")
		)
		(fp_line
			(start -11.554968 -1.171702)
			(end -11.554968 -7.649972)
			(stroke
				(width 0.1524)
				(type default)
			)
			(layer "F.SilkS")
		)
		(fp_line
			(start -11.554968 1.368298)
			(end -11.554968 0.047498)
			(stroke
				(width 0.1524)
				(type default)
			)
			(layer "F.SilkS")
		)
		(fp_line
			(start 11.554968 2.104898)
			(end 11.554968 3.095498)
			(stroke
				(width 0.1524)
				(type default)
			)
			(layer "F.SilkS")
		)
		(fp_line
			(start -11.554968 2.993898)
			(end -11.554968 2.485898)
			(stroke
				(width 0.1524)
				(type default)
			)
			(layer "F.SilkS")
		)
		(fp_line
			(start 11.554968 4.136898)
			(end 11.554968 5.584698)
			(stroke
				(width 0.1524)
				(type default)
			)
			(layer "F.SilkS")
		)
		(fp_line
			(start -11.554968 4.238498)
			(end -11.554968 3.730498)
			(stroke
				(width 0.1524)
				(type default)
			)
			(layer "F.SilkS")
		)
		(fp_line
			(start 11.106658 7.649972)
			(end -9.010142 7.649972)
			(stroke
				(width 0.1524)
				(type default)
			)
			(layer "F.SilkS")
		)
		(fp_line
			(start 6.945122 7.649972)
			(end -6.945122 7.649972)
			(stroke
				(width 0.1524)
				(type default)
			)
			(layer "F.SilkS")
		)
		(fp_line
			(start -11.554968 7.649972)
			(end -11.554968 5.381498)
			(stroke
				(width 0.1524)
				(type default)
			)
			(layer "F.SilkS")
		)
		(fp_poly
			(pts
				(xy -7.112 -4.445) (xy -8.128 -4.953) (xy -8.128 -3.937)
			)
			(stroke
				(width 0)
				(type default)
			)
			(fill yes)
			(layer "F.SilkS")
		)
		(fp_line
			(start 6.945122 -7.649972)
			(end 6.945122 7.649972)
			(stroke
				(width 0.1)
				(type default)
			)
			(layer "F.Fab")
		)
		(fp_line
			(start -6.945122 -7.649972)
			(end 6.945122 -7.649972)
			(stroke
				(width 0.1)
				(type default)
			)
			(layer "F.Fab")
		)
		(fp_line
			(start 6.945122 7.649972)
			(end -6.945122 7.649972)
			(stroke
				(width 0.1)
				(type default)
			)
			(layer "F.Fab")
		)
		(fp_line
			(start -6.945122 7.649972)
			(end -6.945122 -7.649972)
			(stroke
				(width 0.1)
				(type default)
			)
			(layer "F.Fab")
		)
		(fp_poly
			(pts
				(xy -7.112 -4.445) (xy -8.128 -4.953) (xy -8.128 -3.937)
			)
			(stroke
				(width 0)
				(type default)
			)
			(fill yes)
			(layer "F.Fab")
		)
		(fp_text user "16"
			(at 7.49173 -5.2324 0)
			(unlocked yes)
			(layer "F.SilkS")
			(effects
				(font
					(size 0.7874 0.5842)
					(thickness 0.1524)
				)
				(justify left)
			)
		)
		(fp_text user "9"
			(at 7.51713 4.1656 0)
			(unlocked yes)
			(layer "F.SilkS")
			(effects
				(font
					(size 0.7874 0.5842)
					(thickness 0.1524)
				)
				(justify left)
			)
		)
		(fp_text user "8"
			(at -7.77367 4.2164 0)
			(unlocked yes)
			(layer "F.SilkS")
			(effects
				(font
					(size 0.7874 0.5842)
					(thickness 0.1524)
				)
				(justify left)
			)
		)
		(fp_text user "16"
			(at 7.49173 -5.2324 0)
			(unlocked yes)
			(layer "F.Fab")
			(effects
				(font
					(size 0.7874 0.5842)
					(thickness 0.1524)
				)
				(justify left)
			)
		)
		(fp_text user "9"
			(at 7.51713 4.1656 0)
			(unlocked yes)
			(layer "F.Fab")
			(effects
				(font
					(size 0.7874 0.5842)
					(thickness 0.1524)
				)
				(justify left)
			)
		)
		(fp_text user "8"
			(at -7.77367 4.2164 0)
			(unlocked yes)
			(layer "F.Fab")
			(effects
				(font
					(size 0.7874 0.5842)
					(thickness 0.1524)
				)
				(justify left)
			)
		)
		(pad "1" smd rect
			(at -4.800092 -4.445)
			(size 0.508 1.4986)
			(layers "F.Cu" "F.Mask" "F.Paste")
			(net "SPI_PCH_IO3_FLASH_R1")
		)
		(pad "2" smd rect
			(at -4.800092 -3.175)
			(size 0.508 1.4986)
			(layers "F.Cu" "F.Mask" "F.Paste")
			(net "P3V3_AUX")
		)
		(pad "3" smd rect
			(at -4.800092 -1.905)
			(size 0.508 1.4986)
			(layers "F.Cu" "F.Mask" "F.Paste")
			(net "RST_SPI_PCH_FLASH_R1_N")
		)
		(pad "4" smd rect
			(at -4.800092 -0.635)
			(size 0.508 1.4986)
			(layers "F.Cu" "F.Mask" "F.Paste")
			(net "TP_J40_4")
		)
		(pad "5" smd rect
			(at -4.800092 0.635)
			(size 0.508 1.4986)
			(layers "F.Cu" "F.Mask" "F.Paste")
			(net "TP_J40_5")
		)
		(pad "6" smd rect
			(at -4.800092 1.905)
			(size 0.508 1.4986)
			(layers "F.Cu" "F.Mask" "F.Paste")
			(net "TP_J40_6")
		)
		(pad "7" smd rect
			(at -4.800092 3.175)
			(size 0.508 1.4986)
			(layers "F.Cu" "F.Mask" "F.Paste")
			(net "SPI_PCH_CS0_FLASH_R1_N")
		)
		(pad "8" smd rect
			(at -4.800092 4.445)
			(size 0.508 1.4986)
			(layers "F.Cu" "F.Mask" "F.Paste")
			(net "SPI_PCH_IO1_FLASH_R1")
		)
		(pad "9" smd rect
			(at 4.800092 4.445)
			(size 0.508 1.4986)
			(layers "F.Cu" "F.Mask" "F.Paste")
			(net "SPI_PCH_IO2_FLASH_R1")
		)
		(pad "10" smd rect
			(at 4.800092 3.175)
			(size 0.508 1.4986)
			(layers "F.Cu" "F.Mask" "F.Paste")
			(net "GND")
		)
		(pad "11" smd rect
			(at 4.800092 1.905)
			(size 0.508 1.4986)
			(layers "F.Cu" "F.Mask" "F.Paste")
			(net "TP_J40_11")
		)
		(pad "12" smd rect
			(at 4.800092 0.635)
			(size 0.508 1.4986)
			(layers "F.Cu" "F.Mask" "F.Paste")
			(net "TP_J40_12")
		)
		(pad "13" smd rect
			(at 4.800092 -0.635)
			(size 0.508 1.4986)
			(layers "F.Cu" "F.Mask" "F.Paste")
			(net "TP_J40_13")
		)
		(pad "14" smd rect
			(at 4.800092 -1.905)
			(size 0.508 1.4986)
			(layers "F.Cu" "F.Mask" "F.Paste")
			(net "TP_J40_14")
		)
		(pad "15" smd rect
			(at 4.800092 -3.175)
			(size 0.508 1.4986)
			(layers "F.Cu" "F.Mask" "F.Paste")
			(net "SPI_PCH_IO0_FLASH_R1")
		)
		(pad "16" smd rect
			(at 4.800092 -4.445)
			(size 0.508 1.4986)
			(layers "F.Cu" "F.Mask" "F.Paste")
			(net "SPI_PCH_CLK_FLASH_R1")
		)
	)
)
